# BASEBOARD_FAB2 (Tioga Pass) — schematic parts with pin connectivity, parts 4650–4650 of 4751; source: Cadence DE-HDL packaged netlist (pstxprt.dat, pstxnet.dat, pstchip.dat)

U2D1  SKX_EXT_B  IC  pkg BGA1  page 55  (pins 1353-1690 of 3647)
  CC10  UPI2_TX_DN(18)  OUT  = TP_CPU1_UPI2_RSVD_DM21
  CC12  UPI2_TX_DN(19)  OUT  = TP_CPU1_UPI2_RSVD_DT21
  CC14  UPI2_RX_DP(16)  IN  = GND
  CC16  VSS(508)  GROUND  = GND
  CC18  VSS(507)  GROUND  = GND
  CC20  RSVD(112)  BI  = PVCCMCP_CPU1
  CC22  CD_TDO  OUT  = JTAG_MCP_CPU1_TDO
  CC24  VSS(506)  GROUND  = GND
  CC26  VCCIO(83)  POWER  = PVCCIO_CPU1
  CC60  VCCIN(44)  POWER  = PVCCIN_CPU1
  CC62  VCCIN(43)  POWER  = PVCCIN_CPU1
  CC64  VSS(505)  GROUND  = GND
  CC66  VCCSA(22)  POWER  = PVSA_CPU1
  CC68  VCCSA(21)  POWER  = PVSA_CPU1
  CC70  VCCSA(20)  POWER  = PVSA_CPU1
  CC72  VSS(504)  GROUND  = GND
  CC74  VSS(503)  GROUND  = GND
  CC76  VSS(502)  GROUND  = GND
  CC78  VSS(501)  GROUND  = GND
  CC80  VSS(500)  GROUND  = GND
  CC82  VSS(499)  GROUND  = GND
  CC84  VCCIN(42)  POWER  = PVCCIN_CPU1
  CD3  PE2_TX_DP(8)  OUT  = TP_P3E_CPU1_PE2_RSR_TXP<8>
  CD5  VSS(498)  GROUND  = GND
  CD7  PE2_RX_DP(6)  IN  = TP_P3E_CPU1_PE2_RSR_RXP<6>
  CD9  VCCIO(27)  POWER  = PVCCIO_CPU1
  CD11  UPI2_TX_DP(17)  OUT  = TP_CPU1_UPI2_RSVD_DK19
  CD13  VSS(497)  GROUND  = GND
  CD15  UPI2_RX_DN(16)  IN  = GND
  CD17  UPI2_RX_DP(17)  IN  = GND
  CD19  RSVD(110)  BI  = PVCCMCP_CPU1
  CD21  RSVD(109)  BI  = PVCCMCP_CPU1
  CD23  CD_TRST_N  IN  = JTAG_MCP_TRST_N
  CD25  RSVD(108)  BI  = TP_CPU1_RSVD_108
  CD27  VCCIO(82)  POWER  = PVCCIO_CPU1
  CD61  VCCIN(41)  POWER  = PVCCIN_CPU1
  CD63  VSS(496)  GROUND  = GND
  CD65  VCCSA(19)  POWER  = PVSA_CPU1
  CD67  VCCSA(18)  POWER  = PVSA_CPU1
  CD69  VCCSA(17)  POWER  = PVSA_CPU1
  CD71  VCCSA(16)  POWER  = PVSA_CPU1
  CD73  VSS(495)  GROUND  = GND
  CD75  VSS(494)  GROUND  = GND
  CD77  VSS(493)  GROUND  = GND
  CD79  VSS(492)  GROUND  = GND
  CD81  VSS(491)  GROUND  = GND
  CD83  VCCIN(40)  POWER  = PVCCIN_CPU1
  CD85  VCCIN(39)  POWER  = PVCCIN_CPU1
  CE2  PE2_TX_DP(6)  OUT  = TP_P3E_CPU1_PE2_RSR_TXP<6>
  CE4  PE2_TX_DP(7)  OUT  = TP_P3E_CPU1_PE2_RSR_TXP<7>
  CE6  PE2_RX_DN(6)  IN  = TP_P3E_CPU1_PE2_RSR_RXN<6>
  CE8  PE2_RX_DN(7)  IN  = TP_P3E_CPU1_PE2_RSR_RXN<7>
  CE10  VSS(490)  GROUND  = GND
  CE12  UPI2_TX_DN(17)  OUT  = TP_CPU1_UPI2_RSVD_DL20
  CE14  VSS(489)  GROUND  = GND
  CE16  UPI2_RX_DN(15)  IN  = GND
  CE18  VCCIO(26)  POWER  = PVCCIO_CPU1
  CE20  VSS(488)  GROUND  = GND
  CE22  RSVD(107)  BI  = PVCCMCP_CPU1
  CE24  CD_TMS  IN  = JTAG_MCP_TMS
  CE26  VSS(487)  GROUND  = GND
  CE60  VCCIN(38)  POWER  = PVCCIN_CPU1
  CE62  VSS(486)  GROUND  = GND
  CE64  VCCSA(15)  POWER  = PVSA_CPU1
  CE66  VCCSA(14)  POWER  = PVSA_CPU1
  CE68  VCCSA(13)  POWER  = PVSA_CPU1
  CE70  VSS(485)  GROUND  = GND
  CE72  VCCSA(12)  POWER  = PVSA_CPU1
  CE74  VCCSA(11)  POWER  = PVSA_CPU1
  CE76  VCCSA_SENSE  POWER  = VSENSE_PVSA_CPU1_SKT_VSEN
  CE78  RSVD(106)  BI  = TP_CPU1_RSVD_106
  CE80  RSVD(105)  BI  = TP_CPU1_RSVD_105
  CE82  VSS(484)  GROUND  = GND
  CE84  VCCIN(37)  POWER  = PVCCIN_CPU1
  CF3  PE2_TX_DN(7)  OUT  = TP_P3E_CPU1_PE2_RSR_TXN<7>
  CF5  VCCIO(9)  POWER  = PVCCIO_CPU1
  CF7  PE2_RX_DP(5)  IN  = TP_P3E_CPU1_PE2_RSR_RXP<5>
  CF9  VSS(482)  GROUND  = GND
  CF11  UPI2_TX_DP(16)  OUT  = TP_CPU1_UPI2_RSVD_DJ20
  CF13  UPI2_TX_DN(15)  OUT  = TP_CPU1_UPI2_RSVD_DH19
  CF15  UPI2_RX_DP(15)  IN  = GND
  CF17  UPI2_RX_DN(17)  IN  = GND
  CF19  RSVD(104)  BI  = PVCCMCP_CPU1
  CF21  RSVD(103)  BI  = PVCCMCP_CPU1
  CF23  RSVD(102)  BI  = PVCCMCP_CPU1
  CF25  CD_POR_N  BI  = RST_CD_CPU1_POR_N
  CF27  VCCIO(81)  POWER  = PVCCIO_CPU1
  CF61  VCCIN(36)  POWER  = PVCCIN_CPU1
  CF63  VSS(481)  GROUND  = GND
  CF65  VCCSA(10)  POWER  = PVSA_CPU1
  CF67  VCCSA(9)  POWER  = PVSA_CPU1
  CF69  VSS(480)  GROUND  = GND
  CF71  VSS(479)  GROUND  = GND
  CF73  VCCSA(8)  POWER  = PVSA_CPU1
  CF75  VCCSA(7)  POWER  = PVSA_CPU1
  CF77  VSS(478)  GROUND  = GND
  CF79  RSVD(101)  BI  = TP_CPU1_RSVD_101
  CF81  RSVD(100)  BI  = TP_CPU1_RSVD_100
  CF83  VSS(477)  GROUND  = GND
  CF85  VCCIN(35)  POWER  = PVCCIN_CPU1
  CG2  PE2_TX_DN(6)  OUT  = TP_P3E_CPU1_PE2_RSR_TXN<6>
  CG4  DMI_TX_DN(0)  OUT  = TP_CPU1_DMI_TX_DN0
  CG6  VSS(1191)  GROUND  = GND
  CG8  PE2_RX_DN(5)  IN  = TP_P3E_CPU1_PE2_RSR_RXN<5>
  CG10  RSVD(99)  BI  = TP_CPU1_RSVD_99
  CG12  UPI2_TX_DP(15)  OUT  = TP_CPU1_UPI2_RSVD_DJ18
  CG14  VCCIO(10)  POWER  = PVCCIO_CPU1
  CG16  UPI2_RX_DP(14)  IN  = GND
  CG18  VSS(475)  GROUND  = GND
  CG20  RSVD(98)  BI  = PVCCMCP_CPU1
  CG22  VSS(474)  GROUND  = GND
  CG24  RSVD(97)  BI  = TP_CPU1_RSVD_97
  CG26  RSVD(96)  BI  = PVCCMCP_CPU1
  CG60  VCCIN(34)  POWER  = PVCCIN_CPU1
  CG62  VSS(473)  GROUND  = GND
  CG64  VCCSA(6)  POWER  = PVSA_CPU1
  CG66  VCCSA(5)  POWER  = PVSA_CPU1
  CG68  VSS(472)  GROUND  = GND
  CG70  DDR5_DQS_DP(17)  BI  = M_M_DQS_DP<17>
  CG72  VSS(471)  GROUND  = GND
  CG74  VCCSA(4)  POWER  = PVSA_CPU1
  CG76  VSS_VCCSA_SENSE  POWER  = VSENSE_PVSA_CPU1_SKT_VRTN
  CG78  RSVD(95)  BI  = TP_CPU1_RSVD_95
  CG80  VSS(470)  GROUND  = GND
  CG82  RSVD(94)  BI  = TP_CPU1_RSVD_94
  CG84  VCCIN(33)  POWER  = PVCCIN_CPU1
  CH1  VSS(469)  GROUND  = GND
  CH3  VSS(468)  GROUND  = GND
  CH5  DMI_TX_DP(0)  OUT  = TP_CPU1_DMI_TX_DP0
  CH7  PE2_RX_DP(4)  IN  = TP_P3E_CPU1_PE2_RSR_RXP<4>
  CH9  VCCIO(24)  POWER  = PVCCIO_CPU1
  CH11  UPI2_TX_DN(16)  OUT  = TP_CPU1_UPI2_RSVD_DG20
  CH13  UPI2_TX_DP(14)  OUT  = TP_CPU1_UPI2_RSVD_DH17
  CH15  VSS(467)  GROUND  = GND
  CH17  UPI2_RX_DN(14)  IN  = GND
  CH19  VSS(466)  GROUND  = GND
  CH21  RSVD(93)  BI  = PVCCMCP_CPU1
  CH23  RSVD(92)  BI  = PVCCMCP_CPU1
  CH25  RSVD(91)  BI  = TP_CPU1_RSVD_91
  CH27  VCCIO(85)  POWER  = PVCCIO_CPU1
  CH61  VCCIN(32)  POWER  = PVCCIN_CPU1
  CH63  VSS(465)  GROUND  = GND
  CH65  VCCSA(3)  POWER  = PVSA_CPU1
  CH67  VSS(464)  GROUND  = GND
  CH69  DDR5_ECC(6)  BI  = M_M_ECC<6>
  CH71  DDR5_ECC(0)  BI  = M_M_ECC<0>
  CH73  VSS(463)  GROUND  = GND
  CH75  VCCSA(2)  POWER  = PVSA_CPU1
  CH77  RSVD(90)  BI  = TP_CPU1_RSVD_90
  CH79  VSS(462)  GROUND  = GND
  CH81  VSS(461)  GROUND  = GND
  CH83  VSS(460)  GROUND  = GND
  CH85  VCCIN(31)  POWER  = PVCCIN_CPU1
  CJ2  VSS(459)  GROUND  = GND
  CJ4  DMI_TX_DN(1)  OUT  = TP_CPU1_DMI_TX_DN1
  CJ6  VSS(458)  GROUND  = GND
  CJ8  VSS(457)  GROUND  = GND
  CJ10  VSS(456)  GROUND  = GND
  CJ12  VSS(455)  GROUND  = GND
  CJ14  UPI2_TX_DN(14)  OUT  = TP_CPU1_UPI2_RSVD_DK17
  CJ16  UPI2_RX_DP(12)  IN  = GND
  CJ18  UPI2_RX_DN(13)  IN  = GND
  CJ20  RSVD(89)  BI  = PVCCMCP_CPU1
  CJ22  RSVD(88)  BI  = PVCCMCP_CPU1
  CJ24  RSVD(87)  BI  = PVCCMCP_CPU1
  CJ26  RSVD(86)  BI  = PVCCMCP_CPU1
  CJ28  VCCIO(84)  POWER  = PVCCIO_CPU1
  CJ60  VCCIN(30)  POWER  = PVCCIN_CPU1
  CJ62  VSS(452)  GROUND  = GND
  CJ64  VCCSA(1)  POWER  = PVSA_CPU1
  CJ66  VCCSA(0)  POWER  = PVSA_CPU1
  CJ68  DDR5_ECC(2)  BI  = M_M_ECC<2>
  CJ70  DDR5_DQS_DN(17)  BI  = M_M_DQS_DN<17>
  CJ72  DDR5_ECC(4)  BI  = M_M_ECC<4>
  CJ74  VSS(451)  GROUND  = GND
  CJ76  VSS(450)  GROUND  = GND
  CJ78  VSS(449)  GROUND  = GND
  CJ80  DDR4_DQ(5)  BI  = M_L_DQ<5>
  CJ82  VSS(448)  GROUND  = GND
  CJ84  VSS(447)  GROUND  = GND
  CJ86  VSS(446)  GROUND  = GND
  CK1  PE2_TX_DP(4)  OUT  = TP_P3E_CPU1_PE2_RSR_TXP<4>
  CK3  PE2_TX_DP(5)  OUT  = TP_P3E_CPU1_PE2_RSR_TXP<5>
  CK5  VCCIO(22)  POWER  = PVCCIO_CPU1
  CK7  PE2_RX_DN(4)  IN  = TP_P3E_CPU1_PE2_RSR_RXN<4>
  CK9  DMI_RX_DN(0)  IN  = TP_CPU1_DMI_RX_DN0
  CK11  VSS(445)  GROUND  = GND
  CK13  UPI2_TX_DP(13)  OUT  = TP_CPU1_UPI2_RSVD_DF17
  CK15  VSS(444)  GROUND  = GND
  CK17  UPI2_RX_DP(13)  IN  = GND
  CK19  RSVD(85)  BI  = TP_CPU1_RSVD_85
  CK21  VSS(443)  GROUND  = GND
  CK23  RSVD(84)  BI  = PVCCMCP_CPU1
  CK25  RSVD(83)  BI  = PVCCMCP_CPU1
  CK27  VSS(442)  GROUND  = GND
  CK29  UPI2_RBIAS(1)  IN  = A_CPU1_UPI2_RBIAS
  CK59  VCCIN(29)  POWER  = PVCCIN_CPU1
  CK61  VCCIN(28)  POWER  = PVCCIN_CPU1
  CK63  VSS(441)  GROUND  = GND
  CK65  VSS(440)  GROUND  = GND
  CK67  VSS(439)  GROUND  = GND
  CK69  VSS(438)  GROUND  = GND
  CK71  VSS(437)  GROUND  = GND
  CK73  VSS(436)  GROUND  = GND
  CK75  VSS(435)  GROUND  = GND
  CK77  RSVD(82)  BI  = TP_CPU1_RSVD_82
  CK79  DDR4_DQ(4)  BI  = M_L_DQ<4>
  CK81  DDR4_DQ(1)  BI  = M_L_DQ<1>
  CK83  VSS(434)  GROUND  = GND
  CK85  VSS(433)  GROUND  = GND
  CL2  PE2_TX_DN(5)  OUT  = TP_P3E_CPU1_PE2_RSR_TXN<5>
  CL4  DMI_TX_DP(1)  OUT  = TP_CPU1_DMI_TX_DP1
  CL6  PE2_RX_DP(3)  IN  = TP_P3E_CPU1_PE2_RSR_RXP<3>
  CL8  VSS(432)  GROUND  = GND
  CL10  DMI_RX_DP(0)  IN  = TP_CPU1_DMI_RX_DP0
  CL12  VCCIO(21)  POWER  = PVCCIO_CPU1
  CL14  VSS(431)  GROUND  = GND
  CL16  UPI2_RX_DN(12)  IN  = GND
  CL18  VSS(430)  GROUND  = GND
  CL20  VCCIO(11)  POWER  = PVCCIO_CPU1
  CL22  VSS(124)  GROUND  = GND
  CL24  RSVD(81)  BI  = PVCCMCP_CPU1
  CL26  RSVD(80)  BI  = PVCCMCP_CPU1
  CL28  UPI2_RBIAS(0)  IN  = A_CPU1_UPI2_RBIAS
  CL30  PE012_RBIAS(1)  BI  = A_CPU1_PE012_RBIAS
  CL58  VCCIN(27)  POWER  = PVCCIN_CPU1
  CL60  VCCIN(26)  POWER  = PVCCIN_CPU1
  CL62  VSS(427)  GROUND  = GND
  CL64  VSS(426)  GROUND  = GND
  CL66  VSS(425)  GROUND  = GND
  CL68  DDR5_ECC(3)  BI  = M_M_ECC<3>
  CL70  DDR5_DQS_DP(8)  BI  = M_M_DQS_DP<8>
  CL72  DDR5_ECC(5)  BI  = M_M_ECC<5>
  CL74  VSS(424)  GROUND  = GND
  CL76  VSS(423)  GROUND  = GND
  CL78  VSS(422)  GROUND  = GND
  CL80  VSS(421)  GROUND  = GND
  CL82  DDR4_DQS_DN(0)  BI  = M_L_DQS_DN<0>
  CL84  DDR3_DQ(4)  BI  = M_K_DQ<4>
  CL86  DDR3_DQ(5)  BI  = M_K_DQ<5>
  CM1  PE2_TX_DN(4)  OUT  = TP_P3E_CPU1_PE2_RSR_TXN<4>
  CM3  DMI_TX_DP(2)  OUT  = TP_CPU1_DMI_TX_DP2
  CM5  VSS(418)  GROUND  = GND
  CM7  PE2_RX_DN(3)  IN  = TP_P3E_CPU1_PE2_RSR_RXN<3>
  CM9  PE2_RX_DP(1)  IN  = TP_P3E_CPU1_PE2_RSR_RXP<1>
  CM11  DMI_RX_DN(1)  IN  = TP_CPU1_DMI_RX_DN1
  CM13  UPI2_TX_DN(13)  OUT  = TP_CPU1_UPI2_RSVD_DG18
  CM15  VCCIO(20)  POWER  = PVCCIO_CPU1
  CM19  VSS(420)  GROUND  = GND
  CM21  UPI2_RX_DP(11)  IN  = GND
  CM23  RSVD(79)  BI  = PVCCMCP_CPU1
  CM25  RSVD(78)  BI  = PVCCMCP_CPU1
  CM27  VSS(1168)  GROUND  = GND
  CM29  VSS(419)  GROUND  = GND
  CM31  VSS(417)  GROUND  = GND
  CM57  VCCIN(25)  POWER  = PVCCIN_CPU1
  CM59  VCCIN(24)  POWER  = PVCCIN_CPU1
  CM61  VSS(416)  GROUND  = GND
  CM63  VSS(415)  GROUND  = GND
  CM65  DDR5_DQS_DP(12)  BI  = M_M_DQS_DP<12>
  CM67  VSS(414)  GROUND  = GND
  CM69  DDR5_ECC(7)  BI  = M_M_ECC<7>
  CM71  DDR5_ECC(1)  BI  = M_M_ECC<1>
  CM73  VSS(413)  GROUND  = GND
  CM75  DDR5_DQ(5)  BI  = M_M_DQ<5>
  CM77  VSS(412)  GROUND  = GND
  CM79  DDR4_DQ(0)  BI  = M_L_DQ<0>
  CM81  DDR4_DQS_DP(0)  BI  = M_L_DQS_DP<0>
  CM83  VSS(411)  GROUND  = GND
  CM85  VSS(410)  GROUND  = GND
  CN2  VSS(409)  GROUND  = GND
  CN4  DMI_TX_DN(2)  OUT  = TP_CPU1_DMI_TX_DN2
  CN6  VCCIO(19)  POWER  = PVCCIO_CPU1
  CN8  PE2_RX_DP(2)  IN  = TP_P3E_CPU1_PE2_RSR_RXP<2>
  CN10  DMI_RX_DP(1)  IN  = TP_CPU1_DMI_RX_DP1
  CN12  VSS(408)  GROUND  = GND
  CN14  VSS(94)  GROUND  = GND
  CN18  UPI2_RX_DP(9)  IN  = GND
  CN20  UPI2_RX_DN(10)  IN  = GND
  CN22  RSVD(77)  BI  = TP_CPU1_KTI2_AMONV
  CN24  RSVD(76)  BI  = PVCCMCP_CPU1
  CN26  VSS(406)  GROUND  = GND
  CN28  RSVD(75)  BI  = PD_CPU1_MCP01_DMON
  CN30  PE012_RBIAS(0)  BI  = A_CPU1_PE012_RBIAS
  CN32  VSS(405)  GROUND  = GND
  CN56  VCCIN(23)  POWER  = PVCCIN_CPU1
  CN58  VCCIN(22)  POWER  = PVCCIN_CPU1
  CN60  VSS(404)  GROUND  = GND
  CN62  VSS(403)  GROUND  = GND
  CN64  DDR5_DQ(30)  BI  = M_M_DQ<30>
  CN66  DDR5_DQ(24)  BI  = M_M_DQ<24>
  CN68  VSS(402)  GROUND  = GND
  CN70  DDR5_DQS_DN(8)  BI  = M_M_DQS_DN<8>
  CN74  DDR5_DQ(4)  BI  = M_M_DQ<4>
  CN76  DDR5_DQ(1)  BI  = M_M_DQ<1>
  CN78  VSS(401)  GROUND  = GND
  CN80  DDR4_DQS_DN(9)  BI  = M_L_DQS_DN<9>
  CN82  DDR4_DQ(7)  BI  = M_L_DQ<7>
  CN84  DDR3_DQ(0)  BI  = M_K_DQ<0>
  CN86  DDR3_DQ(1)  BI  = M_K_DQ<1>
  CP1  VSS(400)  GROUND  = GND
  CP3  PE2_TX_DP(3)  OUT  = TP_P3E_CPU1_PE2_RSR_TXP<3>
  CP5  DMI_TX_DN(3)  OUT  = TP_CPU1_DMI_TX_DN3
  CP7  PE2_RX_DN(2)  IN  = TP_P3E_CPU1_PE2_RSR_RXN<2>
  CP9  PE2_RX_DN(1)  IN  = TP_P3E_CPU1_PE2_RSR_RXN<1>
  CP11  DMI_RX_DP(2)  IN  = TP_CPU1_DMI_RX_DP2
  CP13  VCCIO(12)  POWER  = PVCCIO_CPU1
  CP19  UPI2_RX_DP(10)  IN  = GND
  CP21  UPI2_RX_DN(11)  IN  = GND
  CP23  RSVD(74)  BI  = PVCCMCP_CPU1
  CP25  VSS(398)  GROUND  = GND
  CP27  BCLK1_DP  IN  = CLK_100M_CPU1_BCLK1_DP
  CP29  PE3_RBIAS(0)  IN  = A_CPU1_PE3_RBIAS
  CP31  RSVD(73)  BI  = TP_CPU1_RSVD_73
  CP33  VCCIN(21)  POWER  = PVCCIN_CPU1
  CP55  VCCIN(20)  POWER  = PVCCIN_CPU1
  CP57  VCCIN(19)  POWER  = PVCCIN_CPU1
  CP59  VSS(397)  GROUND  = GND
  CP61  DDR3_CAVREF  OUT  = M_K_CPU_VREF
  CP63  DDR5_DQ(26)  BI  = M_M_DQ<26>
  CP65  DDR5_DQS_DN(12)  BI  = M_M_DQS_DN<12>
  CP67  DDR5_DQ(28)  BI  = M_M_DQ<28>
  CP69  VSS(396)  GROUND  = GND
  CP73  VSS(395)  GROUND  = GND
  CP75  VSS(394)  GROUND  = GND
  CP77  DDR5_DQS_DN(0)  BI  = M_M_DQS_DN<0>
  CP79  DDR4_DQS_DP(9)  BI  = M_L_DQS_DP<9>
  CP81  VSS(393)  GROUND  = GND
  CP83  VSS(392)  GROUND  = GND
  CP85  DDR3_DQS_DP(9)  BI  = M_K_DQS_DP<9>
  CR2  PE2_TX_DP(2)  OUT  = TP_P3E_CPU1_PE2_RSR_TXP<2>
  CR4  DMI_TX_DP(3)  OUT  = TP_CPU1_DMI_TX_DP3
  CR6  VSS(391)  GROUND  = GND
  CR8  PE2_RX_DP(0)  IN  = TP_P3E_CPU1_PE2_RSR_RXP<0>
  CR10  VSS(390)  GROUND  = GND
  CR12  DMI_RX_DN(2)  IN  = TP_CPU1_DMI_RX_DN2
  CR14  UPI2_TX_DP(12)  OUT  = TP_CPU1_UPI2_RSVD_DE16
  CR18  UPI2_RX_DN(9)  IN  = GND
